(kicad_pcb
	(version 20260206)
	(generator "pcbnew")
	(generator_version "10.0")
	(general
		(thickness 1.6)
		(legacy_teardrops no)
	)
	(paper "A4")
	(title_block
		(title "01162023_DA0F0TEBIF0_F0T_Expander_BD_F_brd_V02_OCP.brd")
		(comment 1 "Grand Teton / footprints 1142-1148 of 9728")
	)
	(layers
		(0 "F.Cu" signal "TOP")
		(4 "In1.Cu" signal "GND")
		(6 "In2.Cu" signal "VCC")
		(8 "In3.Cu" signal "VCC1")
		(10 "In4.Cu" signal "GND1")
		(12 "In5.Cu" signal "IN1")
		(14 "In6.Cu" signal "GND2")
		(16 "In7.Cu" signal "IN2")
		(18 "In8.Cu" signal "GND3")
		(20 "In9.Cu" signal "IN3")
		(22 "In10.Cu" signal "GND4")
		(24 "In11.Cu" signal "IN4")
		(26 "In12.Cu" signal "GND5")
		(28 "In13.Cu" signal "IN5")
		(30 "In14.Cu" signal "GND6")
		(32 "In15.Cu" signal "IN6")
		(34 "In16.Cu" signal "GND7")
		(2 "B.Cu" signal "BOTTOM")
		(9 "F.Adhes" user "F.Adhesive")
		(11 "B.Adhes" user "B.Adhesive")
		(13 "F.Paste" user "Package Geometry/Pastemask Top")
		(15 "B.Paste" user "Package Geometry/Pastemask Bottom")
		(5 "F.SilkS" user "Ref Des/Silkscreen Top")
		(7 "B.SilkS" user "Ref Des/Silkscreen Bottom")
		(1 "F.Mask" user "Board Geometry/Soldermask Top")
		(3 "B.Mask" user "Board Geometry/Soldermask Bottom")
		(17 "Dwgs.User" user "User.Drawings")
		(19 "Cmts.User" user "User.Comments")
		(21 "Eco1.User" user "User.Eco1")
		(23 "Eco2.User" user "User.Eco2")
		(25 "Edge.Cuts" user "Board Geometry/Outline")
		(27 "Margin" user)
		(31 "F.CrtYd" user "Package Geometry/Place Bound Top")
		(29 "B.CrtYd" user "Package Geometry/Place Bound Bottom")
		(35 "F.Fab" user "Ref Des/Assembly Top")
		(33 "B.Fab" user "Ref Des/Assembly Bottom")
	)
	(footprint ""
		(layer "F.Cu")
		(at 71.471536 -25.342342 -90)
		(property "Reference" "R415"
			(at 0 0 270)
			(layer "F.SilkS")
			(hide yes)
			(effects
				(font
					(size 1.27 1.27)
				)
			)
		)
		(property "Value" ""
			(at 0 0 270)
			(layer "F.Fab")
			(effects
				(font
					(size 1.27 1.27)
				)
			)
		)
		(duplicate_pad_numbers_are_jumpers no)
		(fp_line
			(start -0.7874 0.4064)
			(end -0.7874 -0.4064)
			(stroke
				(width 0.1524)
				(type default)
			)
			(layer "F.SilkS")
		)
		(fp_line
			(start 0.7874 0.4064)
			(end -0.7874 0.4064)
			(stroke
				(width 0.1524)
				(type default)
			)
			(layer "F.SilkS")
		)
		(fp_line
			(start -0.7874 -0.4064)
			(end 0.7874 -0.4064)
			(stroke
				(width 0.1524)
				(type default)
			)
			(layer "F.SilkS")
		)
		(fp_line
			(start 0.7874 -0.4064)
			(end 0.7874 0.4064)
			(stroke
				(width 0.1524)
				(type default)
			)
			(layer "F.SilkS")
		)
		(fp_line
			(start -0.67945 0.3048)
			(end -0.67945 -0.305054)
			(stroke
				(width 0.1)
				(type default)
			)
			(layer "F.Fab")
		)
		(fp_line
			(start -0.12065 0.3048)
			(end -0.67945 0.3048)
			(stroke
				(width 0.1)
				(type default)
			)
			(layer "F.Fab")
		)
		(fp_line
			(start 0.120396 0.3048)
			(end 0.120396 0.2794)
			(stroke
				(width 0.1)
				(type default)
			)
			(layer "F.Fab")
		)
		(fp_line
			(start 0.67945 0.3048)
			(end 0.120396 0.3048)
			(stroke
				(width 0.1)
				(type default)
			)
			(layer "F.Fab")
		)
		(fp_line
			(start -0.12065 0.2794)
			(end -0.12065 0.3048)
			(stroke
				(width 0.1)
				(type default)
			)
			(layer "F.Fab")
		)
		(fp_line
			(start 0.120396 0.2794)
			(end -0.12065 0.2794)
			(stroke
				(width 0.1)
				(type default)
			)
			(layer "F.Fab")
		)
		(fp_line
			(start -0.12065 -0.2794)
			(end 0.12065 -0.2794)
			(stroke
				(width 0.1)
				(type default)
			)
			(layer "F.Fab")
		)
		(fp_line
			(start 0.12065 -0.2794)
			(end 0.12065 -0.3048)
			(stroke
				(width 0.1)
				(type default)
			)
			(layer "F.Fab")
		)
		(fp_line
			(start 0.12065 -0.3048)
			(end 0.67945 -0.3048)
			(stroke
				(width 0.1)
				(type default)
			)
			(layer "F.Fab")
		)
		(fp_line
			(start 0.67945 -0.3048)
			(end 0.67945 0.3048)
			(stroke
				(width 0.1)
				(type default)
			)
			(layer "F.Fab")
		)
		(fp_line
			(start -0.67945 -0.305054)
			(end -0.12065 -0.305054)
			(stroke
				(width 0.1)
				(type default)
			)
			(layer "F.Fab")
		)
		(fp_line
			(start -0.12065 -0.305054)
			(end -0.12065 -0.2794)
			(stroke
				(width 0.1)
				(type default)
			)
			(layer "F.Fab")
		)
		(pad "1" smd circle
			(at -0.40005 0 270)
			(size 0 0)
			(layers "F.Cu" "F.Mask" "F.Paste")
			(net "P3V3_SSD2")
		)
		(pad "2" smd circle
			(at 0.40005 0 270)
			(size 0 0)
			(layers "F.Cu" "F.Mask" "F.Paste")
			(net "DUALPORT_N_SSD2")
		)
	)
	(footprint ""
		(layer "F.Cu")
		(at 323.893434 -215.42883 180)
		(property "Reference" "R6645"
			(at 0 0 180)
			(layer "F.SilkS")
			(hide yes)
			(effects
				(font
					(size 1.27 1.27)
				)
			)
		)
		(property "Value" ""
			(at 0 0 180)
			(layer "F.Fab")
			(effects
				(font
					(size 1.27 1.27)
				)
			)
		)
		(duplicate_pad_numbers_are_jumpers no)
		(fp_line
			(start 0.7874 0.4064)
			(end -0.7874 0.4064)
			(stroke
				(width 0.1524)
				(type default)
			)
			(layer "F.SilkS")
		)
		(fp_line
			(start 0.7874 -0.4064)
			(end 0.7874 0.4064)
			(stroke
				(width 0.1524)
				(type default)
			)
			(layer "F.SilkS")
		)
		(fp_line
			(start -0.7874 0.4064)
			(end -0.7874 -0.4064)
			(stroke
				(width 0.1524)
				(type default)
			)
			(layer "F.SilkS")
		)
		(fp_line
			(start -0.7874 -0.4064)
			(end 0.7874 -0.4064)
			(stroke
				(width 0.1524)
				(type default)
			)
			(layer "F.SilkS")
		)
		(fp_line
			(start 0.67945 0.3048)
			(end 0.120396 0.3048)
			(stroke
				(width 0.1)
				(type default)
			)
			(layer "F.Fab")
		)
		(fp_line
			(start 0.67945 -0.3048)
			(end 0.67945 0.3048)
			(stroke
				(width 0.1)
				(type default)
			)
			(layer "F.Fab")
		)
		(fp_line
			(start 0.12065 -0.2794)
			(end 0.12065 -0.3048)
			(stroke
				(width 0.1)
				(type default)
			)
			(layer "F.Fab")
		)
		(fp_line
			(start 0.12065 -0.3048)
			(end 0.67945 -0.3048)
			(stroke
				(width 0.1)
				(type default)
			)
			(layer "F.Fab")
		)
		(fp_line
			(start 0.120396 0.3048)
			(end 0.120396 0.2794)
			(stroke
				(width 0.1)
				(type default)
			)
			(layer "F.Fab")
		)
		(fp_line
			(start 0.120396 0.2794)
			(end -0.12065 0.2794)
			(stroke
				(width 0.1)
				(type default)
			)
			(layer "F.Fab")
		)
		(fp_line
			(start -0.12065 0.3048)
			(end -0.67945 0.3048)
			(stroke
				(width 0.1)
				(type default)
			)
			(layer "F.Fab")
		)
		(fp_line
			(start -0.12065 0.2794)
			(end -0.12065 0.3048)
			(stroke
				(width 0.1)
				(type default)
			)
			(layer "F.Fab")
		)
		(fp_line
			(start -0.12065 -0.2794)
			(end 0.12065 -0.2794)
			(stroke
				(width 0.1)
				(type default)
			)
			(layer "F.Fab")
		)
		(fp_line
			(start -0.12065 -0.305054)
			(end -0.12065 -0.2794)
			(stroke
				(width 0.1)
				(type default)
			)
			(layer "F.Fab")
		)
		(fp_line
			(start -0.67945 0.3048)
			(end -0.67945 -0.305054)
			(stroke
				(width 0.1)
				(type default)
			)
			(layer "F.Fab")
		)
		(fp_line
			(start -0.67945 -0.305054)
			(end -0.12065 -0.305054)
			(stroke
				(width 0.1)
				(type default)
			)
			(layer "F.Fab")
		)
		(pad "1" smd circle
			(at -0.40005 0 180)
			(size 0 0)
			(layers "F.Cu" "F.Mask" "F.Paste")
			(net "HSC_D_OC_FPGA_N")
		)
		(pad "2" smd circle
			(at 0.40005 0 180)
			(size 0 0)
			(layers "F.Cu" "F.Mask" "F.Paste")
			(net "HSC_D_OC_BUF_R_N")
		)
	)
	(footprint ""
		(layer "F.Cu")
		(at 106.614214 -215.047576)
		(property "Reference" "PC285"
			(at 0 0 0)
			(layer "F.SilkS")
			(hide yes)
			(effects
				(font
					(size 1.27 1.27)
				)
			)
		)
		(property "Value" ""
			(at 0 0 0)
			(layer "F.Fab")
			(effects
				(font
					(size 1.27 1.27)
				)
			)
		)
		(duplicate_pad_numbers_are_jumpers no)
		(fp_line
			(start -1.524 -0.762)
			(end 1.524 -0.762)
			(stroke
				(width 0.1524)
				(type default)
			)
			(layer "F.SilkS")
		)
		(fp_line
			(start -1.524 0.762)
			(end -1.524 -0.762)
			(stroke
				(width 0.1524)
				(type default)
			)
			(layer "F.SilkS")
		)
		(fp_line
			(start 1.524 -0.762)
			(end 1.524 0.762)
			(stroke
				(width 0.1524)
				(type default)
			)
			(layer "F.SilkS")
		)
		(fp_line
			(start 1.524 0.762)
			(end -1.524 0.762)
			(stroke
				(width 0.1524)
				(type default)
			)
			(layer "F.SilkS")
		)
		(fp_line
			(start -1.1049 -0.724916)
			(end -1.1049 0.724916)
			(stroke
				(width 0.1)
				(type default)
			)
			(layer "F.Fab")
		)
		(fp_line
			(start -1.1049 0.724916)
			(end 1.1049 0.724916)
			(stroke
				(width 0.1)
				(type default)
			)
			(layer "F.Fab")
		)
		(fp_line
			(start 1.1049 -0.724916)
			(end -1.1049 -0.724916)
			(stroke
				(width 0.1)
				(type default)
			)
			(layer "F.Fab")
		)
		(fp_line
			(start 1.1049 0.724916)
			(end 1.1049 -0.724916)
			(stroke
				(width 0.1)
				(type default)
			)
			(layer "F.Fab")
		)
		(pad "1" smd rect
			(at -0.889 0 180)
			(size 1.016 1.27)
			(layers "F.Cu" "F.Mask" "F.Paste")
			(net "SW_P12V_P1V8_PEX_FLT")
		)
		(pad "2" smd rect
			(at 0.889 0 180)
			(size 1.016 1.27)
			(layers "F.Cu" "F.Mask" "F.Paste")
			(net "GND")
		)
	)
	(footprint ""
		(layer "F.Cu")
		(at 379.307344 -257.439414 -90)
		(property "Reference" "C3576"
			(at 0 0 270)
			(layer "F.SilkS")
			(hide yes)
			(effects
				(font
					(size 1.27 1.27)
				)
			)
		)
		(property "Value" ""
			(at 0 0 270)
			(layer "F.Fab")
			(effects
				(font
					(size 1.27 1.27)
				)
			)
		)
		(duplicate_pad_numbers_are_jumpers no)
		(fp_line
			(start -0.299974 0.150114)
			(end -0.299974 -0.150114)
			(stroke
				(width 0.1)
				(type default)
			)
			(layer "F.Fab")
		)
		(fp_line
			(start 0.299974 0.150114)
			(end -0.299974 0.150114)
			(stroke
				(width 0.1)
				(type default)
			)
			(layer "F.Fab")
		)
		(fp_line
			(start -0.299974 -0.150114)
			(end 0.299974 -0.150114)
			(stroke
				(width 0.1)
				(type default)
			)
			(layer "F.Fab")
		)
		(fp_line
			(start 0.299974 -0.150114)
			(end 0.299974 0.150114)
			(stroke
				(width 0.1)
				(type default)
			)
			(layer "F.Fab")
		)
		(pad "1" smd rect
			(at -0.2667 0 270)
			(size 0.3048 0.381)
			(layers "F.Cu" "F.Mask" "F.Paste")
			(net "P1V8_PLL0_PEX3")
		)
		(pad "2" smd rect
			(at 0.2667 0 270)
			(size 0.3048 0.381)
			(layers "F.Cu" "F.Mask" "F.Paste")
			(net "GND")
		)
	)
	(footprint ""
		(layer "F.Cu")
		(at 406.781 -383.667 90)
		(property "Reference" "R6279"
			(at 0 0 90)
			(layer "F.SilkS")
			(hide yes)
			(effects
				(font
					(size 1.27 1.27)
				)
			)
		)
		(property "Value" ""
			(at 0 0 90)
			(layer "F.Fab")
			(effects
				(font
					(size 1.27 1.27)
				)
			)
		)
		(duplicate_pad_numbers_are_jumpers no)
		(fp_line
			(start 0.7874 -0.4064)
			(end 0.7874 0.4064)
			(stroke
				(width 0.1524)
				(type default)
			)
			(layer "F.SilkS")
		)
		(fp_line
			(start -0.7874 -0.4064)
			(end 0.7874 -0.4064)
			(stroke
				(width 0.1524)
				(type default)
			)
			(layer "F.SilkS")
		)
		(fp_line
			(start 0.7874 0.4064)
			(end -0.7874 0.4064)
			(stroke
				(width 0.1524)
				(type default)
			)
			(layer "F.SilkS")
		)
		(fp_line
			(start -0.7874 0.4064)
			(end -0.7874 -0.4064)
			(stroke
				(width 0.1524)
				(type default)
			)
			(layer "F.SilkS")
		)
		(fp_line
			(start -0.12065 -0.305054)
			(end -0.12065 -0.2794)
			(stroke
				(width 0.1)
				(type default)
			)
			(layer "F.Fab")
		)
		(fp_line
			(start -0.67945 -0.305054)
			(end -0.12065 -0.305054)
			(stroke
				(width 0.1)
				(type default)
			)
			(layer "F.Fab")
		)
		(fp_line
			(start 0.67945 -0.3048)
			(end 0.67945 0.3048)
			(stroke
				(width 0.1)
				(type default)
			)
			(layer "F.Fab")
		)
		(fp_line
			(start 0.12065 -0.3048)
			(end 0.67945 -0.3048)
			(stroke
				(width 0.1)
				(type default)
			)
			(layer "F.Fab")
		)
		(fp_line
			(start 0.12065 -0.2794)
			(end 0.12065 -0.3048)
			(stroke
				(width 0.1)
				(type default)
			)
			(layer "F.Fab")
		)
		(fp_line
			(start -0.12065 -0.2794)
			(end 0.12065 -0.2794)
			(stroke
				(width 0.1)
				(type default)
			)
			(layer "F.Fab")
		)
		(fp_line
			(start 0.120396 0.2794)
			(end -0.12065 0.2794)
			(stroke
				(width 0.1)
				(type default)
			)
			(layer "F.Fab")
		)
		(fp_line
			(start -0.12065 0.2794)
			(end -0.12065 0.3048)
			(stroke
				(width 0.1)
				(type default)
			)
			(layer "F.Fab")
		)
		(fp_line
			(start 0.67945 0.3048)
			(end 0.120396 0.3048)
			(stroke
				(width 0.1)
				(type default)
			)
			(layer "F.Fab")
		)
		(fp_line
			(start 0.120396 0.3048)
			(end 0.120396 0.2794)
			(stroke
				(width 0.1)
				(type default)
			)
			(layer "F.Fab")
		)
		(fp_line
			(start -0.12065 0.3048)
			(end -0.67945 0.3048)
			(stroke
				(width 0.1)
				(type default)
			)
			(layer "F.Fab")
		)
		(fp_line
			(start -0.67945 0.3048)
			(end -0.67945 -0.305054)
			(stroke
				(width 0.1)
				(type default)
			)
			(layer "F.Fab")
		)
		(pad "1" smd circle
			(at -0.40005 0 90)
			(size 0 0)
			(layers "F.Cu" "F.Mask" "F.Paste")
			(net "I3C_MB_BMC_R_SDA")
		)
		(pad "2" smd circle
			(at 0.40005 0 90)
			(size 0 0)
			(layers "F.Cu" "F.Mask" "F.Paste")
			(net "I3C_MB_BMC_SDA")
		)
	)
	(footprint ""
		(layer "F.Cu")
		(at 331.73035 -66.32194 -90)
		(property "Reference" "PC877"
			(at 0 0 270)
			(layer "F.SilkS")
			(hide yes)
			(effects
				(font
					(size 1.27 1.27)
				)
			)
		)
		(property "Value" ""
			(at 0 0 270)
			(layer "F.Fab")
			(effects
				(font
					(size 1.27 1.27)
				)
			)
		)
		(duplicate_pad_numbers_are_jumpers no)
		(fp_line
			(start -0.7874 0.4064)
			(end -0.7874 -0.4064)
			(stroke
				(width 0.1524)
				(type default)
			)
			(layer "F.SilkS")
		)
		(fp_line
			(start 0.7874 0.4064)
			(end -0.7874 0.4064)
			(stroke
				(width 0.1524)
				(type default)
			)
			(layer "F.SilkS")
		)
		(fp_line
			(start -0.7874 -0.4064)
			(end 0.7874 -0.4064)
			(stroke
				(width 0.1524)
				(type default)
			)
			(layer "F.SilkS")
		)
		(fp_line
			(start 0.7874 -0.4064)
			(end 0.7874 0.4064)
			(stroke
				(width 0.1524)
				(type default)
			)
			(layer "F.SilkS")
		)
		(fp_line
			(start -0.67945 0.3048)
			(end -0.67945 -0.305054)
			(stroke
				(width 0.1)
				(type default)
			)
			(layer "F.Fab")
		)
		(fp_line
			(start -0.12065 0.3048)
			(end -0.67945 0.3048)
			(stroke
				(width 0.1)
				(type default)
			)
			(layer "F.Fab")
		)
		(fp_line
			(start 0.120396 0.3048)
			(end 0.120396 0.2794)
			(stroke
				(width 0.1)
				(type default)
			)
			(layer "F.Fab")
		)
		(fp_line
			(start 0.67945 0.3048)
			(end 0.120396 0.3048)
			(stroke
				(width 0.1)
				(type default)
			)
			(layer "F.Fab")
		)
		(fp_line
			(start -0.12065 0.2794)
			(end -0.12065 0.3048)
			(stroke
				(width 0.1)
				(type default)
			)
			(layer "F.Fab")
		)
		(fp_line
			(start 0.120396 0.2794)
			(end -0.12065 0.2794)
			(stroke
				(width 0.1)
				(type default)
			)
			(layer "F.Fab")
		)
		(fp_line
			(start -0.12065 -0.2794)
			(end 0.12065 -0.2794)
			(stroke
				(width 0.1)
				(type default)
			)
			(layer "F.Fab")
		)
		(fp_line
			(start 0.12065 -0.2794)
			(end 0.12065 -0.3048)
			(stroke
				(width 0.1)
				(type default)
			)
			(layer "F.Fab")
		)
		(fp_line
			(start 0.12065 -0.3048)
			(end 0.67945 -0.3048)
			(stroke
				(width 0.1)
				(type default)
			)
			(layer "F.Fab")
		)
		(fp_line
			(start 0.67945 -0.3048)
			(end 0.67945 0.3048)
			(stroke
				(width 0.1)
				(type default)
			)
			(layer "F.Fab")
		)
		(fp_line
			(start -0.67945 -0.305054)
			(end -0.12065 -0.305054)
			(stroke
				(width 0.1)
				(type default)
			)
			(layer "F.Fab")
		)
		(fp_line
			(start -0.12065 -0.305054)
			(end -0.12065 -0.2794)
			(stroke
				(width 0.1)
				(type default)
			)
			(layer "F.Fab")
		)
		(pad "1" smd circle
			(at -0.40005 0 270)
			(size 0 0)
			(layers "F.Cu" "F.Mask" "F.Paste")
			(net "P12V_SSD11_CO_DV_DT")
		)
		(pad "2" smd circle
			(at 0.40005 0 270)
			(size 0 0)
			(layers "F.Cu" "F.Mask" "F.Paste")
			(net "GND")
		)
	)
	(footprint ""
		(layer "F.Cu")
		(at 117.226334 -37.929566 90)
		(property "Reference" "R5552"
			(at 0 0 90)
			(layer "F.SilkS")
			(hide yes)
			(effects
				(font
					(size 1.27 1.27)
				)
			)
		)
		(property "Value" ""
			(at 0 0 90)
			(layer "F.Fab")
			(effects
				(font
					(size 1.27 1.27)
				)
			)
		)
		(duplicate_pad_numbers_are_jumpers no)
		(fp_line
			(start 0.7874 -0.4064)
			(end 0.7874 0.4064)
			(stroke
				(width 0.1524)
				(type default)
			)
			(layer "F.SilkS")
		)
		(fp_line
			(start -0.7874 -0.4064)
			(end 0.7874 -0.4064)
			(stroke
				(width 0.1524)
				(type default)
			)
			(layer "F.SilkS")
		)
		(fp_line
			(start 0.7874 0.4064)
			(end -0.7874 0.4064)
			(stroke
				(width 0.1524)
				(type default)
			)
			(layer "F.SilkS")
		)
		(fp_line
			(start -0.7874 0.4064)
			(end -0.7874 -0.4064)
			(stroke
				(width 0.1524)
				(type default)
			)
			(layer "F.SilkS")
		)
		(fp_line
			(start -0.12065 -0.305054)
			(end -0.12065 -0.2794)
			(stroke
				(width 0.1)
				(type default)
			)
			(layer "F.Fab")
		)
		(fp_line
			(start -0.67945 -0.305054)
			(end -0.12065 -0.305054)
			(stroke
				(width 0.1)
				(type default)
			)
			(layer "F.Fab")
		)
		(fp_line
			(start 0.67945 -0.3048)
			(end 0.67945 0.3048)
			(stroke
				(width 0.1)
				(type default)
			)
			(layer "F.Fab")
		)
		(fp_line
			(start 0.12065 -0.3048)
			(end 0.67945 -0.3048)
			(stroke
				(width 0.1)
				(type default)
			)
			(layer "F.Fab")
		)
		(fp_line
			(start 0.12065 -0.2794)
			(end 0.12065 -0.3048)
			(stroke
				(width 0.1)
				(type default)
			)
			(layer "F.Fab")
		)
		(fp_line
			(start -0.12065 -0.2794)
			(end 0.12065 -0.2794)
			(stroke
				(width 0.1)
				(type default)
			)
			(layer "F.Fab")
		)
		(fp_line
			(start 0.120396 0.2794)
			(end -0.12065 0.2794)
			(stroke
				(width 0.1)
				(type default)
			)
			(layer "F.Fab")
		)
		(fp_line
			(start -0.12065 0.2794)
			(end -0.12065 0.3048)
			(stroke
				(width 0.1)
				(type default)
			)
			(layer "F.Fab")
		)
		(fp_line
			(start 0.67945 0.3048)
			(end 0.120396 0.3048)
			(stroke
				(width 0.1)
				(type default)
			)
			(layer "F.Fab")
		)
		(fp_line
			(start 0.120396 0.3048)
			(end 0.120396 0.2794)
			(stroke
				(width 0.1)
				(type default)
			)
			(layer "F.Fab")
		)
		(fp_line
			(start -0.12065 0.3048)
			(end -0.67945 0.3048)
			(stroke
				(width 0.1)
				(type default)
			)
			(layer "F.Fab")
		)
		(fp_line
			(start -0.67945 0.3048)
			(end -0.67945 -0.305054)
			(stroke
				(width 0.1)
				(type default)
			)
			(layer "F.Fab")
		)
		(pad "1" smd circle
			(at -0.40005 0 90)
			(size 0 0)
			(layers "F.Cu" "F.Mask" "F.Paste")
			(net "SSD4_AUX_P3V3_EN_R")
		)
		(pad "2" smd circle
			(at 0.40005 0 90)
			(size 0 0)
			(layers "F.Cu" "F.Mask" "F.Paste")
			(net "SSD4_AUX_P3V3_EN")
		)
	)
)
